# BASEBOARD_FAB2 (Tioga Pass) — schematic parts with pin connectivity, parts 1500–1663 of 4751; source: Cadence DE-HDL packaged netlist (pstxprt.dat, pstxnet.dat, pstchip.dat)

C7F5  CAP  10UF 16V 10% X6S  pkg 0805  page 231 : 1 = VR_FET_SW_P12V_STBY_PVPP_ABC ; 2 = GND
C7F6  CAP_A  0.1UF 16V 10% X7R  pkg 0402V  page 231 : 1 = VR_FET_SW_P12V_STBY_PVPP_ABC ; 2 = GND
C7F7  SC22U16V5MX-4-GP  20%  pkg SMD-BCG5  page 231 : 1 = VR_FET_SW_P12V_STBY_PVPP_ABC ; 2 = GND
C7F8  CAP  1000PF 50V 10% EMPTY  pkg 0402LF  page 231 : 1 = FM_PVPP_CPU0_EN ; 2 = AGND_PVPP_ABC
C7F9  CAP  100.0PF 50V 5% COG  pkg 0402LF  page 231 : 1 = VR_FB_PVPP_ABC ; 2 = VR_COMP_PVPP_ABC_3
C7F10  CAP  0.027UF 16V 10% X7R  pkg 0402  page 231 : 1 = VR_PVPP_ABC_SS ; 2 = AGND_PVPP_ABC
C7F11  CAP  1000PF 50V 10% X7R  pkg 0402LF  page 231 : 1 = PWRGD_PVPP_ABC_R ; 2 = GND
C7F12  CAP  2200PF 50V 10% X7R  pkg 0402LF  page 231 : 1 = VR_COMP_RC_PVPP_ABC ; 2 = VR_COMP_PVPP_ABC_3
C7F13  CAP  2200PF 50V 10% X7R  pkg 0402LF  page 231 : 1 = VR_COMP_PVPP_ABC ; 2 = VR_FB_PVPP_ABC
C7F14  CAP  1000PF 50V 10% X7R  pkg 0402LF  page 215 : 1 = PWRGD_PVDDQ_ABC_R ; 2 = GND
C7F15  CAP_A  0.1UF 16V 10% X7R  pkg 0402V  page 215 : 1 = VR_PVDDQ_ABC_VD12 ; 2 = GND
C7F16  CAP_A  1.0UF 6.3V 10% X6S  pkg 0402V  page 215 : 1 = VR_PVDDQ_ABC_VD12 ; 2 = GND
C7F17  CAP_A  0.1UF 16V 10% X7R  pkg 0402V  page 215 : 1 = VR_PVDDQ_ABC_VDD ; 2 = GND
C7F18  CAP_A  1.0UF 6.3V 10% X6S  pkg 0402V  page 215 : 1 = VR_PVDDQ_ABC_VDD ; 2 = GND
C7G2  CAPP  270UF 16V 20% OSCON  pkg 2626  page 217 : 1 = VR_FET_SW_P12V_STBY_PVDDQ_ABC ; 2 = GND
C7G3  CAP  220PF 50V 10% X7R  pkg 0402LF  page 215 : 1 = A_TSENSE_PVDDQ_ABC ; 2 = GND
C7G4  CAP  220PF 50V 10% X7R  pkg 0402LF  page 215 : 1 = VR_PVDDQ_ABC_AVSP ; 2 = VSENSE_PVDDQ_ABC_N
C7G5  CAP  0.22UF 16V 10% X7R  pkg 0402  page 105 : 1 = P3E_CPU0_PE2_SS_TXP<15> ; 2 = P3E_CPU0_PE2_SS_C_TXP<15>
C7G6  CAP  0.22UF 16V 10% X7R  pkg 0402  page 105 : 1 = P3E_CPU0_PE2_SS_TXN<15> ; 2 = P3E_CPU0_PE2_SS_C_TXN<15>
C7G7  CAP  0.22UF 16V 10% X7R  pkg 0402  page 105 : 1 = P3E_CPU0_PE2_SS_TXN<14> ; 2 = P3E_CPU0_PE2_SS_C_TXN<14>
C7G8  CAP  0.22UF 16V 10% X7R  pkg 0402  page 105 : 1 = P3E_CPU0_PE2_SS_TXP<14> ; 2 = P3E_CPU0_PE2_SS_C_TXP<14>
C7G9  CAP  0.22UF 16V 10% X7R  pkg 0402  page 105 : 1 = P3E_CPU0_PE2_SS_TXP<13> ; 2 = P3E_CPU0_PE2_SS_C_TXP<13>
C7G10  CAP  0.22UF 16V 10% X7R  pkg 0402  page 105 : 1 = P3E_CPU0_PE2_SS_TXN<13> ; 2 = P3E_CPU0_PE2_SS_C_TXN<13>
C7G11  CAP  0.22UF 16V 10% X7R  pkg 0402  page 105 : 1 = P3E_CPU0_PE2_SS_TXP<12> ; 2 = P3E_CPU0_PE2_SS_C_TXP<12>
C7G12  CAP  0.22UF 16V 10% X7R  pkg 0402  page 105 : 1 = P3E_CPU0_PE2_SS_TXN<12> ; 2 = P3E_CPU0_PE2_SS_C_TXN<12>
C7G13  CAP  0.22UF 16V 10% X7R  pkg 0402  page 105 : 1 = P3E_CPU0_PE2_SS_TXN<11> ; 2 = P3E_CPU0_PE2_SS_C_TXN<11>
C7G14  CAP  0.22UF 16V 10% X7R  pkg 0402  page 105 : 1 = P3E_CPU0_PE2_SS_TXP<11> ; 2 = P3E_CPU0_PE2_SS_C_TXP<11>
C7G15  CAP  0.22UF 16V 10% X7R  pkg 0402  page 105 : 1 = P3E_CPU0_PE2_SS_TXP<10> ; 2 = P3E_CPU0_PE2_SS_C_TXP<10>
C7G16  CAP  0.22UF 16V 10% X7R  pkg 0402  page 105 : 1 = P3E_CPU0_PE2_SS_TXN<10> ; 2 = P3E_CPU0_PE2_SS_C_TXN<10>
C7G17  CAP  0.22UF 16V 10% X7R  pkg 0402  page 105 : 1 = P3E_CPU0_PE2_SS_TXP<9> ; 2 = P3E_CPU0_PE2_SS_C_TXP<9>
C7G18  CAP  0.22UF 16V 10% X7R  pkg 0402  page 105 : 1 = P3E_CPU0_PE2_SS_TXN<9> ; 2 = P3E_CPU0_PE2_SS_C_TXN<9>
C7G19  CAP  0.22UF 16V 10% X7R  pkg 0402  page 105 : 1 = P3E_CPU0_PE2_SS_TXN<8> ; 2 = P3E_CPU0_PE2_SS_C_TXN<8>
C7G20  CAP  0.22UF 16V 10% X7R  pkg 0402  page 105 : 1 = P3E_CPU0_PE2_SS_TXP<8> ; 2 = P3E_CPU0_PE2_SS_C_TXP<8>
C7G21  CAP  0.22UF 16V 10% X7R  pkg 0402  page 105 : 1 = P3E_CPU0_PE2_SS_TXP<7> ; 2 = P3E_CPU0_PE2_SS_C_TXP<7>
C7G22  CAP  0.22UF 16V 10% X7R  pkg 0402  page 105 : 1 = P3E_CPU0_PE2_SS_TXN<7> ; 2 = P3E_CPU0_PE2_SS_C_TXN<7>
C7G23  CAP  0.22UF 16V 10% X7R  pkg 0402  page 105 : 1 = P3E_CPU0_PE2_SS_TXP<6> ; 2 = P3E_CPU0_PE2_SS_C_TXP<6>
C7G24  CAP  0.22UF 16V 10% X7R  pkg 0402  page 105 : 1 = P3E_CPU0_PE2_SS_TXN<6> ; 2 = P3E_CPU0_PE2_SS_C_TXN<6>
C7G25  CAP  0.22UF 16V 10% X7R  pkg 0402  page 105 : 1 = P3E_CPU0_PE2_SS_TXP<5> ; 2 = P3E_CPU0_PE2_SS_C_TXP<5>
C7G26  CAP  0.22UF 16V 10% X7R  pkg 0402  page 105 : 1 = P3E_CPU0_PE2_SS_TXN<5> ; 2 = P3E_CPU0_PE2_SS_C_TXN<5>
C7G27  CAP  22UF 4V 20% X6S  pkg 0805LF  page 216 : 1 = PVDDQ_ABC ; 2 = GND
C7G28  CAPP  470UF 2.5V 20% ALUM  pkg 3018  page 217 : 1 = PVDDQ_ABC ; 2 = GND
C7G29  CAP_A  0.1UF 16V 10% X7R  pkg 0402V  page 216 : 1 = VR_FET_SW_P12V_STBY_PVDDQ_ABC ; 2 = GND
C7G30  CAP  1.0UF 16V 10% X6S  pkg 0402  page 216 : 1 = VR_FET_SW_P12V_STBY_PVDDQ_ABC ; 2 = GND
C7G31  CAP  0.220UF 16V 10% X7R  pkg 0402  page 216 : 1 = VR_PVDDQ_ABC_PH1_BOOT ; 2 = VR_PVDDQ_ABC_PH1_PHASE
C7G33  CAP  1.0UF 16V 10% X6S  pkg 0402  page 216 : 1 = VR_PVDDQ_ABC_PH1_VCIN ; 2 = GND
C7G34  CAP  0.22UF 16V 10% X7R  pkg 0402  page 216 : 1 = P5V_STBY ; 2 = GND
C7G35  SC1U10V2KX-4-GP  10%  pkg SMD-BCG6  page 216 : 1 = P5V_STBY ; 2 = GND
C7G36  CAP_A  0.1UF 16V 10% X7R  pkg 0402V  page 216 : 1 = VR_FET_SW_P12V_STBY_PVDDQ_ABC ; 2 = GND
C7G37  CAP  1.0UF 16V 10% X6S  pkg 0402  page 216 : 1 = VR_FET_SW_P12V_STBY_PVDDQ_ABC ; 2 = GND
C7G38  CAP  0.220UF 16V 10% X7R  pkg 0402  page 216 : 1 = VR_PVDDQ_ABC_PH2_BOOT ; 2 = VR_PVDDQ_ABC_PH2_PHASE
C7G40  CAP  1.0UF 16V 10% X6S  pkg 0402  page 216 : 1 = VR_PVDDQ_ABC_PH2_VCIN ; 2 = GND
C7G41  CAP  0.22UF 16V 10% X7R  pkg 0402  page 216 : 1 = P5V_STBY ; 2 = GND
C7G42  SC1U10V2KX-4-GP  10%  pkg SMD-BCG6  page 216 : 1 = P5V_STBY ; 2 = GND
C7L1  CAP  100UF 4V 20% X5R  pkg 0805  page 228 : 1 = PVDDQ_KLM ; 2 = GND
C7L2  CAP  10UF 4V 20% X6S  pkg 0603LF  page 234 : 1 = PVPP_KLM ; 2 = GND
C7L3  CAP  10UF 4V 20% X6S  pkg 0603LF  page 234 : 1 = PVPP_KLM ; 2 = GND
C7L4  CAP_A  47UF 4V 20% X5R  pkg 0603V  page 228 : 1 = PVDDQ_KLM ; 2 = GND
C7L5  CAP_A  47UF 4V 20% X5R  pkg 0603V  page 228 : 1 = PVDDQ_KLM ; 2 = GND
C7L6  CAP  10UF 4V 20% X6S  pkg 0603LF  page 234 : 1 = PVPP_KLM ; 2 = GND
C7L7  CAP  10UF 4V 20% X6S  pkg 0603LF  page 234 : 1 = PVPP_KLM ; 2 = GND
C7M1  CAP_A  47UF 4V 20% X5R  pkg 0603V  page 228 : 1 = PVDDQ_KLM ; 2 = GND
C7M2  CAP_A  47UF 4V 20% X5R  pkg 0603V  page 228 : 1 = PVDDQ_KLM ; 2 = GND
C7M3  CAP  10UF 4V 20% X6S  pkg 0603LF  page 234 : 1 = PVPP_KLM ; 2 = GND
C7M4  CAP  10UF 4V 20% X6S  pkg 0603LF  page 234 : 1 = PVPP_KLM ; 2 = GND
C7M5  CAP_A  47UF 4V 20% X5R  pkg 0603V  page 228 : 1 = PVDDQ_KLM ; 2 = GND
C7M6  CAPP  68UF 16V 20% TANT  pkg 3018  page 195 : 1 = P12V_STBY ; 2 = GND
C7P1  CAP  100UF 4V 20% X5R  pkg 0805  page 228 : 1 = PVDDQ_KLM ; 2 = GND
C7P2  CAP  100UF 4V 20% X5R  pkg 0805  page 228 : 1 = PVDDQ_KLM ; 2 = GND
C7P3  CAP  47UF 4V 20% X6S  pkg 0805  page 76 : 1 = PVCCIO_CPU1 ; 2 = GND
C7P4  CAP  100UF 4V 20% X5R  pkg 0805  page 76 : 1 = PVCCMCP_CPU1 ; 2 = GND
C7P5  CAP  100UF 4V 20% X5R  pkg 0805  page 76 : 1 = PVCCMCP_CPU1 ; 2 = GND
C7P6  CAP  100UF 4V 20% X5R  pkg 0805  page 76 : 1 = PVCCMCP_CPU1 ; 2 = GND
C7P7  CAP  100UF 4V 20% X5R  pkg 0805  page 76 : 1 = PVCCMCP_CPU1 ; 2 = GND
C7P8  CAP  100UF 4V 20% X5R  pkg 0805  page 76 : 1 = PVCCMCP_CPU1 ; 2 = GND
C7P9  CAP  100UF 4V 20% X5R  pkg 0805  page 76 : 1 = PVCCMCP_CPU1 ; 2 = GND
C7P10  CAP  100UF 4V 20% X5R  pkg 0805  page 76 : 1 = PVCCMCP_CPU1 ; 2 = GND
C7P11  CAP  100UF 4V 20% X5R  pkg 0805  page 76 : 1 = PVCCMCP_CPU1 ; 2 = GND
C7P12  CAP_A  22.0UF 4V 20% X6S  pkg 0603V  page 76 : 1 = PVCCIO_CPU1 ; 2 = GND
C7P13  CAP  100UF 4V 20% X5R  pkg 0805  page 76 : 1 = PVCCMCP_CPU1 ; 2 = GND
C7P14  CAP  100UF 4V 20% X5R  pkg 0805  page 76 : 1 = PVCCMCP_CPU1 ; 2 = GND
C7P15  CAP  100UF 4V 20% X5R  pkg 0805  page 76 : 1 = PVCCMCP_CPU1 ; 2 = GND
C7P16  CAP_A  22.0UF 4V 20% X6S  pkg 0603V  page 76 : 1 = PVCCIO_CPU1 ; 2 = GND
C7P17  CAP  47UF 4V 20% X6S  pkg 0805  page 76 : 1 = PVCCIO_CPU1 ; 2 = GND
C7P18  CAP  47UF 4V 20% X6S  pkg 0805  page 76 : 1 = PVCCIO_CPU1 ; 2 = GND
C7P19  CAP  47UF 4V 20% X6S  pkg 0805  page 76 : 1 = PVCCIN_CPU1 ; 2 = GND
C7P20  CAP  100UF 4V 20% X5R  pkg 0805  page 225 : 1 = PVDDQ_GHJ ; 2 = GND
C7R1  CAP_A  22.0UF 4V 20% X6S  pkg 0603V  page 214 : 1 = PVCCIO_CPU1 ; 2 = GND
C7T1  CAP  100UF 4V 20% X5R  pkg 0805  page 225 : 1 = PVDDQ_GHJ ; 2 = GND
C7T2  CAP  10UF 4V 20% X6S  pkg 0603LF  page 233 : 1 = PVPP_GHJ ; 2 = GND
C7T3  CAP  10UF 4V 20% X6S  pkg 0603LF  page 233 : 1 = PVPP_GHJ ; 2 = GND
C7T4  CAP_A  47UF 4V 20% X5R  pkg 0603V  page 225 : 1 = PVDDQ_GHJ ; 2 = GND
C7T5  CAP_A  47UF 4V 20% X5R  pkg 0603V  page 225 : 1 = PVDDQ_GHJ ; 2 = GND
C7U1  CAP_A  47UF 4V 20% X5R  pkg 0603V  page 225 : 1 = PVDDQ_GHJ ; 2 = GND
C7U2  CAP_A  47UF 4V 20% X5R  pkg 0603V  page 225 : 1 = PVDDQ_GHJ ; 2 = GND
C7U3  CAP  10UF 4V 20% X6S  pkg 0603LF  page 233 : 1 = PVPP_GHJ ; 2 = GND
C7U4  CAP  10UF 4V 20% X6S  pkg 0603LF  page 233 : 1 = PVPP_GHJ ; 2 = GND
C7U5  CAP  10UF 4V 20% X6S  pkg 0603LF  page 233 : 1 = PVPP_GHJ ; 2 = GND
C7U6  CAP  10UF 4V 20% X6S  pkg 0603LF  page 233 : 1 = PVPP_GHJ ; 2 = GND
C7U7  CAP  100UF 4V 20% X5R  pkg 0805  page 225 : 1 = PVDDQ_GHJ ; 2 = GND
C7W1  CAP_A  0.1UF 16V 10% X7R  pkg 0402V  page 166 : 1 = P3V3_STBY ; 2 = GND
C7W2  SE100U16VM-48-GP  pkg SMD-TCG2  page 220 : 1 = VR_FET_SW_P12V_STBY_PVDDQ_DEF ; 2 = GND
C7W5  SC22U16V5MX-4-GP  20%  pkg SMD-BCG5  page 220 : 1 = VR_FET_SW_P12V_STBY_PVDDQ_DEF ; 2 = GND
C7W6  SC22U16V5MX-4-GP  20%  pkg SMD-BCG5  page 220 : 1 = VR_FET_SW_P12V_STBY_PVDDQ_DEF ; 2 = GND
C7W7  SC22U16V5MX-4-GP  20%  pkg SMD-BCG5  page 220 : 1 = VR_FET_SW_P12V_STBY_PVDDQ_DEF ; 2 = GND
C7W8  SC22U16V5MX-4-GP  20%  pkg SMD-BCG5  page 220 : 1 = VR_FET_SW_P12V_STBY_PVDDQ_DEF ; 2 = GND
C7W9  SC22U16V5MX-4-GP  20%  pkg SMD-BCG5  page 220 : 1 = VR_FET_SW_P12V_STBY_PVDDQ_DEF ; 2 = GND
C7W10  SC22U16V5MX-4-GP  20%  pkg SMD-BCG5  page 220 : 1 = VR_FET_SW_P12V_STBY_PVDDQ_DEF ; 2 = GND
C7W11  SC22U16V5MX-4-GP  20%  pkg SMD-BCG5  page 220 : 1 = VR_FET_SW_P12V_STBY_PVDDQ_DEF ; 2 = GND
C7W12  SC22U16V5MX-4-GP  20%  pkg SMD-BCG5  page 220 : 1 = VR_FET_SW_P12V_STBY_PVDDQ_DEF ; 2 = GND
C7W13  SC22U16V5MX-4-GP  20%  pkg SMD-BCG5  page 220 : 1 = VR_FET_SW_P12V_STBY_PVDDQ_DEF ; 2 = GND
C8A2  CAP  220PF 50V 10% X7R  pkg 0402LF  page 235 : 1 = VR_PVNN_PCH_AVSP ; 2 = VSENSE_PVNN_PCH_STBY_AVSN
C8A3  CAP_A  0.1UF 16V 10% X7R  pkg 0402V  page 235 : 1 = VR_PVNN_PCH_VINSEN ; 2 = GND
C8A4  CAP  0.1UF 25V 10% X7R  pkg 0603LF  page 237 : 1 = P3V3_STBY ; 2 = GND
C8A6  CAP  10UF 6.3V 20% X6S  pkg 0603  page 237 : 1 = P3V3_STBY ; 2 = GND
C8A7  CAP_A  1.0UF 6.3V 10% X6S  pkg 0402V  page 235 : 1 = VR_PVNN_P1V05_PCH_VD12 ; 2 = GND
C8A8  CAP_A  0.1UF 16V 10% X7R  pkg 0402V  page 235 : 1 = VR_PVNN_P1V05_PCH_VD12 ; 2 = GND
C8A9  CAP  1000PF 50V 10% X7R  pkg 0402LF  page 235 : 1 = PWRGD_PVNN_PCH_R ; 2 = GND
C8A10  CAP  1000PF 50V 10% EMPTY  pkg 0402LF  page 237 : 1 = PWRGD_P3V3_STBY ; 2 = GND
C8A11  CAP  1000PF 50V 10% X7R  pkg 0402LF  page 237 : 1 = PWRGD_P1V8_PCH_STBY_R ; 2 = GND
C8A12  CAP  47UF 4V 20% X6S  pkg 0805  page 237 : 1 = P1V8_PCH_STBY ; 2 = GND
C8A13  CAP  47UF 4V 20% X6S  pkg 0805  page 131 : 1 = P1V05_PCH_STBY ; 2 = GND
C8A14  CAP  22UF 6.3V 20% X6S  pkg 0805  page 237 : 1 = P1V8_PCH_STBY ; 2 = GND
C8A15  CAPP  470UF 2V 20% ALUM  pkg SM  page 236 : 1 = P1V05_PCH_STBY ; 2 = GND
C8B1  CAP_A  22.0UF 4V 20% X6S  pkg 0603V  page 130 : 1 = P1V8_PCH_STBY ; 2 = GND
C8B2  CAP_A  22.0UF 4V 20% X6S  pkg 0603V  page 130 : 1 = P1V8_PCH_STBY ; 2 = GND
C8B3  CAP_A  22.0UF 4V 20% X6S  pkg 0603V  page 130 : 1 = P1V8_PCH_STBY ; 2 = GND
C8B4  CAP_A  22.0UF 4V 20% X6S  pkg 0603V  page 130 : 1 = P1V8_PCH_STBY ; 2 = GND
C8B5  CAP_A  0.1UF 16V 10% X7R  pkg 0402V  page 198 : 1 = P5V_STBY ; 2 = GND
C8B6  CAP  10UF 16V 10% X6S  pkg 0805  page 198 : 1 = P5V ; 2 = GND
C8B7  CAP_A  0.1UF 16V 10% X7R  pkg 0402V  page 198 : 1 = P5V ; 2 = GND
C8B8  CAP_A  0.1UF 16V 10% X7R  pkg 0402V  page 198 : 1 = P5V_STBY ; 2 = GND
C8B9  CAP_A  22.0UF 4V 20% X6S  pkg 0603V  page 131 : 1 = P1V05_PCH_STBY ; 2 = GND
C8B10  CAP_A  22.0UF 4V 20% X6S  pkg 0603V  page 131 : 1 = P1V05_PCH_STBY ; 2 = GND
C8B11  CAP_A  22.0UF 4V 20% X6S  pkg 0603V  page 131 : 1 = P1V05_PCH_STBY ; 2 = GND
C8B12  CAP  10UF 16V 10% X6S  pkg 0805  page 198 : 1 = P5V_STBY ; 2 = GND
C8B13  CAP_A  22.0UF 4V 20% X6S  pkg 0603V  page 131 : 1 = P1V05_PCH_STBY ; 2 = GND
C8B14  CAP_A  22.0UF 4V 20% X6S  pkg 0603V  page 131 : 1 = P1V05_PCH_STBY ; 2 = GND
C8B15  CAP  47UF 4V 20% X6S  pkg 0805  page 131 : 1 = P1V05_PCH_STBY ; 2 = GND
C8B16  CAP  47UF 4V 20% X6S  pkg 0805  page 131 : 1 = P1V05_PCH_STBY ; 2 = GND
C8C1  CAP  33.0PF 50V 5% COG  pkg 0402LF  page 118 : 1 = XTAL_KR_25M_IN ; 2 = GND
C8C2  CAP  33.0PF 50V 5% COG  pkg 0402LF  page 118 : 1 = XTAL_KR_25M_OUT ; 2 = GND
C8C3  CAP  10UF 6.3V 20% X6S  pkg 0603  page 130 : 1 = P3V3_STBY ; 2 = GND
C8C4  CAP  10UF 6.3V 20% X6S  pkg 0603  page 130 : 1 = P3V3_STBY ; 2 = GND
C8C5  CAP  10UF 6.3V 20% X6S  pkg 0603  page 130 : 1 = P3V3_STBY ; 2 = GND
C8C6  CAP  10UF 6.3V 20% X6S  pkg 0603  page 130 : 1 = P3V3_STBY ; 2 = GND
C8C12  CAP_A  0.1UF 16V 10% X7R  pkg 0402V  page 188 : 1 = KR_P1_OCP_RX_DP ; 2 = KR_P1_OCP_RX_C_DP
C8C13  CAP_A  0.1UF 16V 10% X7R  pkg 0402V  page 188 : 1 = KR_P1_OCP_RX_DN ; 2 = KR_P1_OCP_RX_C_DN
C8C14  CAP_A  0.1UF 16V 10% X7R  pkg 0402V  page 188 : 1 = KR_P0_OCP_RX_DN ; 2 = KR_P0_OCP_RX_C_DN
C8C15  CAP_A  0.1UF 16V 10% X7R  pkg 0402V  page 188 : 1 = KR_P0_OCP_RX_DP ; 2 = KR_P0_OCP_RX_C_DP
C8D1  CAP_A  0.1UF 16V 10% X7R  pkg 0402V  page 157 : 1 = P3V3_STBY ; 2 = GND
C8D2  CAP_A  0.1UF 16V 10% X7R  pkg 0402V  page 170 : 1 = P3V3_STBY ; 2 = GND
C8D3  CAP  470PF 50V 10% EMPTY  pkg 0402LF  page 170 : 1 = IRQ_SML1_PMBUS_ALERT_N ; 2 = GND
C8D4  CAP_A  0.1UF 16V 10% X7R  pkg 0402V  page 196 : 1 = P3V3_STBY ; 2 = GND
C8E1  CAP_A  0.1UF 16V 10% X7R  pkg 0402V  page 181 : 1 = P3V3_STBY ; 2 = GND
C8E2  CAP_A  0.1UF 16V 10% X7R  pkg 0402V  page 170 : 1 = P3V3_STBY ; 2 = GND
C8E3  CAP_A  0.1UF 16V 10% X7R  pkg 0402V  page 196 : 1 = PWRGD_P12V_HSC ; 2 = GND
C8E4  ST220U10VDM-LGP  IRP=2400MA  pkg SMD-TCG  page 241 : 1 = P5V_STBY ; 2 = GND
C8E5  CAP_A  0.1UF 16V 10% X7R  pkg 0402V  page 142 : 1 = P3V3_STBY ; 2 = GND
C8E6  CAP  0.1UF 25V 10% X7R  pkg 0603LF  page 241 : 1 = VR_P5V_STBY_BOOT ; 2 = VR_P5V_STBY_PHASE
C8E7  SC22U16V5MX-4-GP  20%  pkg SMD-BCG5  page 241 : 1 = P5V_STBY ; 2 = GND
C8E8  CAP_A  0.1UF 16V 10% X7R  pkg 0402V  page 136 : 1 = P3V3_STBY ; 2 = GND
C8E9  SC22U16V5MX-4-GP  20%  pkg SMD-BCG5  page 241 : 1 = P5V_STBY ; 2 = GND
C8E10  CAP  22UF 16V 10% X6S  pkg 1206LF  page 240 : 1 = VR_FET_SW_P12V_STBY_P3V3_STBY ; 2 = GND
C8E11  SC22U16V5MX-4-GP  20%  pkg SMD-BCG5  page 240 : 1 = VR_FET_SW_P12V_STBY_P3V3_STBY ; 2 = GND
